FILE_TYPE = MACRO_DRAWING;
SET COLOR_WIRE YELLOW;
SET COLOR_PROP ORANGE;
SET COLOR_DOT WHITE;
SET COLOR_ARC YELLOW;
SET COLOR_BODY GREEN;
SET COLOR_NOTE PURPLE;
SET PROP_DISPLAY VALUE;
SET PAGE_NUMBER P368;
FORCEADD OFFPAGE..1
(-5825 2750);
FORCEPROP 2 LAST $XR3 243 
J 0
(-6437 2750);
DISPLAY 0.638298 (-6437 2750);
PAINT MONO (-6437 2750);
FORCEPROP 2 LAST $XR2 189 
J 0
(-6317 2750);
DISPLAY 0.638298 (-6317 2750);
PAINT MONO (-6317 2750);
FORCEPROP 2 LAST $XR1 268 
J 0
(-6197 2750);
DISPLAY 0.638298 (-6197 2750);
PAINT MONO (-6197 2750);
FORCEPROP 2 LAST $XR0 263 
J 0
(-6077 2750);
DISPLAY 0.638298 (-6077 2750);
PAINT MONO (-6077 2750);
FORCEPROP 2 LAST CDS_LIB standard
J 0
(-5825 2750);
DISPLAY INVISIBLE (-5825 2750);
FORCEPROP 1 LAST OFFPAGE TRUE
J 0
(-5500 2625);
DISPLAY 0.872340 (-5500 2625);
DISPLAY INVISIBLE (-5500 2625);
FORCEPROP 1 LAST COMMENT_BODY TRUE
J 0
(-5700 2650);
DISPLAY 1.170213 (-5700 2650);
PAINT GREEN (-5700 2650);
DISPLAY INVISIBLE (-5700 2650);
FORCEPROP 2 LAST PATH I1
J 0
(-5775 2825);
DISPLAY 0.680851 (-5775 2825);
DISPLAY INVISIBLE (-5775 2825);
FORCEADD MOSFET_NCH_DUAL..2
(-4825 4200);
FORCEPROP 1 LAST LOCATION Q144
J 0
(-4674 4176);
DISPLAY 0.723404 (-4674 4176);
PAINT GREEN (-4674 4176);
FORCEPROP 0 LAST $SEC 2
J 0
(-4650 4325);
DISPLAY 0.680851 (-4650 4325);
PAINT MONO (-4650 4325);
DISPLAY INVISIBLE (-4650 4325);
FORCEPROP 0 LAST CDS_SEC 2
J 0
(-4650 4325);
DISPLAY 1.021277 (-4650 4325);
DISPLAY INVISIBLE (-4650 4325);
FORCEPROP 0 LASTPIN (-4775 4400) $PN 3
R 1
J 0
(-4785 4410);
DISPLAY 0.680851 (-4785 4410);
PAINT MONO (-4785 4410);
FORCEPROP 0 LASTPIN (-5025 4150) $PN 5
J 2
(-5035 4160);
DISPLAY 0.680851 (-5035 4160);
PAINT MONO (-5035 4160);
FORCEPROP 0 LASTPIN (-4775 4000) $PN 4
R 1
J 2
(-4785 3990);
DISPLAY 0.680851 (-4785 3990);
PAINT MONO (-4785 3990);
FORCEPROP 2 LAST VALUE PJT138K
J 0
(-4650 4225);
DISPLAY 1.021277 (-4650 4225);
FORCEPROP 1 LAST MATERIAL IC
J 0
(-4674 4051);
DISPLAY 0.723404 (-4674 4051);
PAINT GREEN (-4674 4051);
FORCEPROP 2 LAST PART_TYPE SMLF
J 0
(-4650 4275);
DISPLAY 1.021277 (-4650 4275);
FORCEPROP 2 LAST CDS_LIB pure_quanta
J 0
(-4825 4200);
DISPLAY INVISIBLE (-4825 4200);
FORCEPROP 1 LAST NEEDS_NO_SIZE TRUE
J 0
(-4675 4091);
DISPLAY 0.468085 (-4675 4091);
PAINT GREEN (-4675 4091);
DISPLAY INVISIBLE (-4675 4091);
FORCEPROP 1 LAST CDS_LMAN_SYM_OUTLINE -150,150,150,-150
J 0
(-4825 4200);
DISPLAY 0.468085 (-4825 4200);
PAINT GREEN (-4825 4200);
DISPLAY INVISIBLE (-4825 4200);
FORCEPROP 1 LAST PATH I10
J 0
(-4675 4050);
DISPLAY 0.723404 (-4675 4050);
PAINT GREEN (-4675 4050);
DISPLAY INVISIBLE (-4675 4050);
FORCEPROP 1 LAST PART_NUMBER BAM138K0003
J 0
(-4674 4106);
DISPLAY 0.723404 (-4674 4106);
PAINT GREEN (-4674 4106);
DISPLAY INVISIBLE (-4674 4106);
FORCEADD Q_RES..2
(-4775 4625);
FORCEPROP 1 LAST LOCATION R4605
J 0
(-4730 4750);
DISPLAY 0.638298 (-4730 4750);
FORCEPROP 2 LAST $SEC 1
J 0
(-4725 4850);
DISPLAY 0.680851 (-4725 4850);
PAINT MONO (-4725 4850);
DISPLAY INVISIBLE (-4725 4850);
FORCEPROP 2 LAST CDS_SEC 1
J 0
(-4725 4850);
DISPLAY 1.021277 (-4725 4850);
DISPLAY INVISIBLE (-4725 4850);
FORCEPROP 1 LASTPIN (-4775 4725) $PN 1
J 0
(-4770 4687);
DISPLAY 0.787234 (-4770 4687);
FORCEPROP 1 LASTPIN (-4775 4525) $PN 2
J 0
(-4770 4535);
DISPLAY 0.787234 (-4770 4535);
FORCEPROP 1 LAST TOLERANCE 1%
J 0
(-4730 4650);
DISPLAY 0.638298 (-4730 4650);
FORCEPROP 1 LAST VALUE 1K
J 0
(-4730 4700);
DISPLAY 0.638298 (-4730 4700);
FORCEPROP 1 LAST WATTAGE 1/16W
J 0
(-4735 4600);
DISPLAY 0.638298 (-4735 4600);
FORCEPROP 1 LAST MATERIAL CHIP
J 0
(-4735 4550);
DISPLAY 0.638298 (-4735 4550);
FORCEPROP 1 LAST PACK_TYPE 0402LF
J 0
(-4735 4500);
DISPLAY 0.638298 (-4735 4500);
FORCEPROP 2 LAST CDS_LIB pure_quanta
J 0
(-4775 4625);
PAINT MONO (-4775 4625);
DISPLAY INVISIBLE (-4775 4625);
FORCEPROP 1 LAST PATH I11
J 0
(-4725 4800);
DISPLAY 0.978723 (-4725 4800);
PAINT WHITE (-4725 4800);
DISPLAY INVISIBLE (-4725 4800);
FORCEPROP 1 LAST PART_NUMBER CS21002FB06
J 0
(-4735 4450);
DISPLAY 0.638298 (-4735 4450);
DISPLAY INVISIBLE (-4735 4450);
FORCEADD UNIVERSAL_POWER..1
(-4775 4850);
FORCEPROP 3 LASTPIN (-4775 4800) SIG_NAME P3V3_AUX\g
J 0
(-4765 4810);
DISPLAY 0.659574 (-4765 4810);
PAINT MONO (-4765 4810);
DISPLAY INVISIBLE (-4765 4810);
FORCEPROP 1 LAST HDL_POWER P3V3_AUX
J 1
(-4775 4900);
DISPLAY 0.872340 (-4775 4900);
PAINT GREEN (-4775 4900);
FORCEPROP 2 LAST CDS_LIB pure_quanta_power
J 0
(-4775 4850);
PAINT MONO (-4775 4850);
DISPLAY INVISIBLE (-4775 4850);
FORCEPROP 1 LAST PATH I12
J 0
(-4725 4875);
DISPLAY 0.872340 (-4725 4875);
PAINT AQUA (-4725 4875);
DISPLAY INVISIBLE (-4725 4875);
FORCEADD Q_RES..1
(-3500 4450);
FORCEPROP 1 LAST LOCATION R9446
J 0
(-3750 4450);
DISPLAY 0.787234 (-3750 4450);
FORCEPROP 2 LAST $SEC 1
J 0
(-3550 4650);
DISPLAY 0.680851 (-3550 4650);
PAINT MONO (-3550 4650);
DISPLAY INVISIBLE (-3550 4650);
FORCEPROP 2 LAST CDS_SEC 1
J 0
(-3550 4650);
DISPLAY 1.021277 (-3550 4650);
DISPLAY INVISIBLE (-3550 4650);
FORCEPROP 1 LASTPIN (-3600 4450) $PN 1
J 0
(-3588 4462);
DISPLAY 0.787234 (-3588 4462);
FORCEPROP 1 LASTPIN (-3400 4450) $PN 2
J 0
(-3438 4462);
DISPLAY 0.787234 (-3438 4462);
FORCEPROP 1 LAST MATERIAL CHIP
J 0
(-3600 4575);
DISPLAY 0.510638 (-3600 4575);
FORCEPROP 1 LAST WATTAGE 1/16W
J 2
(-3325 4575);
DISPLAY 0.510638 (-3325 4575);
FORCEPROP 1 LAST PACK_TYPE 0402LF
J 0
(-3200 4450);
DISPLAY 0.510638 (-3200 4450);
FORCEPROP 1 LAST TOLERANCE 1%
J 0
(-3275 4450);
DISPLAY 0.510638 (-3275 4450);
FORCEPROP 1 LAST VALUE 33.2
J 2
(-3300 4450);
DISPLAY 0.510638 (-3300 4450);
FORCEPROP 2 LAST CDS_LIB pure_quanta
J 0
(-3500 4450);
PAINT MONO (-3500 4450);
DISPLAY INVISIBLE (-3500 4450);
FORCEPROP 1 LAST PATH I13
J 0
(-3550 4600);
DISPLAY 0.978723 (-3550 4600);
PAINT WHITE (-3550 4600);
DISPLAY INVISIBLE (-3550 4600);
FORCEPROP 1 LAST PART_NUMBER CS03322FB03
J 0
(-3600 4525);
DISPLAY 0.510638 (-3600 4525);
DISPLAY INVISIBLE (-3600 4525);
FORCEADD OFFPAGE..2
(-3025 2750);
FORCEPROP 2 LAST $XR1 255 
J 0
(-2716 2750);
DISPLAY 0.638298 (-2716 2750);
PAINT MONO (-2716 2750);
FORCEPROP 2 LAST $XR0 254 
J 0
(-2836 2750);
DISPLAY 0.638298 (-2836 2750);
PAINT MONO (-2836 2750);
FORCEPROP 2 LAST CDS_LIB standard
J 0
(-3025 2750);
PAINT MONO (-3025 2750);
DISPLAY INVISIBLE (-3025 2750);
FORCEPROP 1 LAST OFFPAGE TRUE
J 0
(-2700 2625);
DISPLAY 0.872340 (-2700 2625);
PAINT GREEN (-2700 2625);
DISPLAY INVISIBLE (-2700 2625);
FORCEPROP 1 LAST COMMENT_BODY TRUE
J 0
(-3070 2655);
DISPLAY 0.872340 (-3070 2655);
PAINT PEACH (-3070 2655);
DISPLAY INVISIBLE (-3070 2655);
FORCEPROP 2 LAST PATH I14
J 0
(-2700 2800);
DISPLAY 0.680851 (-2700 2800);
DISPLAY INVISIBLE (-2700 2800);
FORCEADD OFFPAGE..2
(-3025 2575);
FORCEPROP 2 LAST $XR0 150 
J 0
(-2836 2575);
DISPLAY 0.638298 (-2836 2575);
PAINT MONO (-2836 2575);
FORCEPROP 2 LAST CDS_LIB standard
J 0
(-3025 2575);
DISPLAY INVISIBLE (-3025 2575);
FORCEPROP 1 LAST OFFPAGE TRUE
J 0
(-2700 2450);
DISPLAY 0.872340 (-2700 2450);
PAINT GREEN (-2700 2450);
DISPLAY INVISIBLE (-2700 2450);
FORCEPROP 1 LAST COMMENT_BODY TRUE
J 0
(-3070 2480);
DISPLAY 0.872340 (-3070 2480);
PAINT PEACH (-3070 2480);
DISPLAY INVISIBLE (-3070 2480);
FORCEPROP 2 LAST PATH I15
J 0
(-2700 2625);
DISPLAY 0.680851 (-2700 2625);
DISPLAY INVISIBLE (-2700 2625);
FORCEADD OFFPAGE..2
(-1850 4450);
FORCEPROP 2 LAST $XR0 80 
J 0
(-1661 4450);
DISPLAY 0.638298 (-1661 4450);
PAINT MONO (-1661 4450);
FORCEPROP 2 LAST CDS_LIB standard
J 0
(-1850 4450);
PAINT MONO (-1850 4450);
DISPLAY INVISIBLE (-1850 4450);
FORCEPROP 1 LAST OFFPAGE TRUE
J 0
(-1525 4325);
DISPLAY 1.170213 (-1525 4325);
PAINT GREEN (-1525 4325);
DISPLAY INVISIBLE (-1525 4325);
FORCEPROP 1 LAST COMMENT_BODY TRUE
J 0
(-1895 4355);
DISPLAY 1.170213 (-1895 4355);
PAINT GREEN (-1895 4355);
DISPLAY INVISIBLE (-1895 4355);
FORCEPROP 2 LAST PATH I16
J 0
(-1650 4500);
DISPLAY 0.680851 (-1650 4500);
DISPLAY INVISIBLE (-1650 4500);
FORCEADD OFFPAGE..4
R 2
(-7150 3850);
FORCEPROP 2 LAST $XR1 255 
J 0
(-7552 3850);
DISPLAY 0.638298 (-7552 3850);
PAINT MONO (-7552 3850);
FORCEPROP 2 LAST $XR0 254 
J 0
(-7432 3850);
DISPLAY 0.638298 (-7432 3850);
PAINT MONO (-7432 3850);
FORCEPROP 2 LAST CDS_LIB standard
J 0
(-7150 3850);
DISPLAY INVISIBLE (-7150 3850);
FORCEPROP 1 LAST OFFPAGE TRUE
J 2
(-7475 3725);
DISPLAY 0.872340 (-7475 3725);
PAINT GREEN (-7475 3725);
DISPLAY INVISIBLE (-7475 3725);
FORCEPROP 1 LAST COMMENT_BODY TRUE
J 2
(-7125 3750);
DISPLAY 0.872340 (-7125 3750);
PAINT GREEN (-7125 3750);
DISPLAY INVISIBLE (-7125 3750);
FORCEPROP 2 LAST PATH I2
J 0
(-7400 3900);
DISPLAY 0.680851 (-7400 3900);
DISPLAY INVISIBLE (-7400 3900);
FORCEADD MOSFET_NCH_DUAL..1
(-5975 3900);
FORCEPROP 1 LAST LOCATION Q144
J 0
(-5824 3874);
DISPLAY 0.723404 (-5824 3874);
PAINT GREEN (-5824 3874);
FORCEPROP 0 LAST $SEC 1
J 0
(-5800 4025);
DISPLAY 0.680851 (-5800 4025);
PAINT MONO (-5800 4025);
DISPLAY INVISIBLE (-5800 4025);
FORCEPROP 2 LAST CDS_SEC 1
J 0
(-5800 4025);
DISPLAY 1.021277 (-5800 4025);
DISPLAY INVISIBLE (-5800 4025);
FORCEPROP 0 LASTPIN (-5925 4100) $PN 6
R 1
J 0
(-5935 4110);
DISPLAY 0.680851 (-5935 4110);
PAINT MONO (-5935 4110);
FORCEPROP 0 LASTPIN (-6175 3850) $PN 2
J 2
(-6185 3860);
DISPLAY 0.680851 (-6185 3860);
PAINT MONO (-6185 3860);
FORCEPROP 0 LASTPIN (-5925 3700) $PN 1
R 1
J 2
(-5935 3690);
DISPLAY 0.680851 (-5935 3690);
PAINT MONO (-5935 3690);
FORCEPROP 2 LAST PART_TYPE SMLF
J 0
(-5800 3975);
DISPLAY 1.021277 (-5800 3975);
FORCEPROP 2 LAST VALUE PJT138K
J 0
(-5800 3925);
DISPLAY 1.021277 (-5800 3925);
FORCEPROP 1 LAST MATERIAL IC
J 0
(-5824 3749);
DISPLAY 0.723404 (-5824 3749);
PAINT GREEN (-5824 3749);
FORCEPROP 1 LAST CDS_LMAN_SYM_OUTLINE -150,150,150,-150
J 0
(-5975 3900);
DISPLAY 0.468085 (-5975 3900);
PAINT GREEN (-5975 3900);
DISPLAY INVISIBLE (-5975 3900);
FORCEPROP 1 LAST NEEDS_NO_SIZE TRUE
J 0
(-5975 3899);
DISPLAY 0.468085 (-5975 3899);
PAINT GREEN (-5975 3899);
DISPLAY INVISIBLE (-5975 3899);
FORCEPROP 2 LAST CDS_LIB pure_quanta
J 0
(-5975 3900);
DISPLAY INVISIBLE (-5975 3900);
FORCEPROP 1 LAST PATH I3
J 0
(-5975 3900);
DISPLAY 0.723404 (-5975 3900);
PAINT GREEN (-5975 3900);
DISPLAY INVISIBLE (-5975 3900);
FORCEPROP 1 LAST PART_NUMBER BAM138K0003
J 0
(-5824 3814);
DISPLAY 0.723404 (-5824 3814);
PAINT GREEN (-5824 3814);
DISPLAY INVISIBLE (-5824 3814);
FORCEADD UNIVERSAL_GND..1
(-5925 3525);
FORCEPROP 3 LASTPIN (-5925 3575) SIG_NAME GND\g
J 0
(-5915 3585);
DISPLAY 0.659574 (-5915 3585);
PAINT MONO (-5915 3585);
DISPLAY INVISIBLE (-5915 3585);
FORCEPROP 2 LAST CDS_LIB pure_quanta_power
J 0
(-5925 3525);
DISPLAY INVISIBLE (-5925 3525);
FORCEPROP 1 LAST HDL_POWER GND
J 1
(-5900 3450);
DISPLAY 0.872340 (-5900 3450);
PAINT GREEN (-5900 3450);
DISPLAY INVISIBLE (-5900 3450);
FORCEPROP 1 LAST PATH I4
J 0
(-5850 3525);
DISPLAY 0.872340 (-5850 3525);
PAINT AQUA (-5850 3525);
DISPLAY INVISIBLE (-5850 3525);
FORCEADD Q_RES..2
(-5925 4500);
FORCEPROP 1 LAST LOCATION R4604
J 0
(-5880 4625);
DISPLAY 0.638298 (-5880 4625);
FORCEPROP 2 LAST $SEC 1
J 0
(-5875 4725);
DISPLAY 0.680851 (-5875 4725);
PAINT MONO (-5875 4725);
DISPLAY INVISIBLE (-5875 4725);
FORCEPROP 2 LAST CDS_SEC 1
J 0
(-5875 4725);
DISPLAY 1.021277 (-5875 4725);
DISPLAY INVISIBLE (-5875 4725);
FORCEPROP 1 LASTPIN (-5925 4600) $PN 1
J 0
(-5920 4562);
DISPLAY 0.787234 (-5920 4562);
FORCEPROP 1 LASTPIN (-5925 4400) $PN 2
J 0
(-5920 4410);
DISPLAY 0.787234 (-5920 4410);
FORCEPROP 1 LAST TOLERANCE 5%
J 0
(-5880 4525);
DISPLAY 0.638298 (-5880 4525);
FORCEPROP 1 LAST VALUE 4.7K
J 0
(-5880 4575);
DISPLAY 0.638298 (-5880 4575);
FORCEPROP 1 LAST MATERIAL CHIP
J 0
(-5885 4425);
DISPLAY 0.638298 (-5885 4425);
FORCEPROP 1 LAST WATTAGE 1/16W
J 0
(-5885 4475);
DISPLAY 0.638298 (-5885 4475);
FORCEPROP 1 LAST PACK_TYPE 0402LF
J 0
(-5885 4375);
DISPLAY 0.638298 (-5885 4375);
FORCEPROP 2 LAST CDS_LIB pure_quanta
J 0
(-5925 4500);
PAINT MONO (-5925 4500);
DISPLAY INVISIBLE (-5925 4500);
FORCEPROP 1 LAST PATH I5
J 0
(-5875 4675);
DISPLAY 0.978723 (-5875 4675);
PAINT WHITE (-5875 4675);
DISPLAY INVISIBLE (-5875 4675);
FORCEPROP 1 LAST PART_NUMBER CS24702JB10
J 0
(-5885 4325);
DISPLAY 0.638298 (-5885 4325);
DISPLAY INVISIBLE (-5885 4325);
FORCEADD UNIVERSAL_POWER..1
(-5925 4725);
FORCEPROP 3 LASTPIN (-5925 4675) SIG_NAME P3V3_AUX\g
J 0
(-5915 4685);
DISPLAY 0.659574 (-5915 4685);
PAINT MONO (-5915 4685);
DISPLAY INVISIBLE (-5915 4685);
FORCEPROP 1 LAST HDL_POWER P3V3_AUX
J 1
(-5925 4775);
DISPLAY 0.872340 (-5925 4775);
PAINT GREEN (-5925 4775);
FORCEPROP 2 LAST CDS_LIB pure_quanta_power
J 0
(-5925 4725);
PAINT MONO (-5925 4725);
DISPLAY INVISIBLE (-5925 4725);
FORCEPROP 1 LAST PATH I6
J 0
(-5875 4750);
DISPLAY 0.872340 (-5875 4750);
PAINT AQUA (-5875 4750);
DISPLAY INVISIBLE (-5875 4750);
FORCEADD Q_RES..1
(-4550 2575);
FORCEPROP 1 LAST LOCATION R3048
J 0
(-4750 2575);
DISPLAY 0.510638 (-4750 2575);
FORCEPROP 0 LAST $SEC 1
J 0
(-4750 2625);
DISPLAY 0.680851 (-4750 2625);
PAINT MONO (-4750 2625);
DISPLAY INVISIBLE (-4750 2625);
FORCEPROP 0 LAST CDS_SEC 1
J 0
(-4750 2625);
DISPLAY 1.021277 (-4750 2625);
DISPLAY INVISIBLE (-4750 2625);
FORCEPROP 1 LASTPIN (-4650 2575) $PN 1
J 0
(-4638 2587);
DISPLAY 0.787234 (-4638 2587);
PAINT MONO (-4638 2587);
FORCEPROP 1 LASTPIN (-4450 2575) $PN 2
J 0
(-4488 2587);
DISPLAY 0.787234 (-4488 2587);
PAINT MONO (-4488 2587);
FORCEPROP 1 LAST MATERIAL CHIP
J 0
(-4300 2575);
DISPLAY 0.510638 (-4300 2575);
FORCEPROP 1 LAST TOLERANCE 5%
J 0
(-4375 2575);
DISPLAY 0.510638 (-4375 2575);
FORCEPROP 1 LAST VALUE 0
J 2
(-4400 2575);
DISPLAY 0.510638 (-4400 2575);
FORCEPROP 1 LAST WATTAGE 1/16W
J 2
(-4375 2650);
DISPLAY 0.404255 (-4375 2650);
DISPLAY INVISIBLE (-4375 2650);
FORCEPROP 1 LAST PACK_TYPE 0402LF
J 0
(-4300 2575);
DISPLAY 0.510638 (-4300 2575);
DISPLAY INVISIBLE (-4300 2575);
FORCEPROP 2 LAST CDS_LIB pure_quanta
J 0
(-4550 2575);
DISPLAY INVISIBLE (-4550 2575);
FORCEPROP 1 LAST PATH I7
J 0
(-4600 2725);
DISPLAY 0.978723 (-4600 2725);
PAINT WHITE (-4600 2725);
DISPLAY INVISIBLE (-4600 2725);
FORCEPROP 1 LAST PART_NUMBER CS00002JB13
J 0
(-4600 2625);
DISPLAY 0.404255 (-4600 2625);
DISPLAY INVISIBLE (-4600 2625);
FORCEADD Q_RES..1
(-4550 2750);
FORCEPROP 1 LAST LOCATION R3047
J 0
(-4750 2750);
DISPLAY 0.510638 (-4750 2750);
FORCEPROP 0 LAST $SEC 1
J 0
(-4750 2800);
DISPLAY 0.680851 (-4750 2800);
PAINT MONO (-4750 2800);
DISPLAY INVISIBLE (-4750 2800);
FORCEPROP 0 LAST CDS_SEC 1
J 0
(-4750 2800);
DISPLAY 1.021277 (-4750 2800);
DISPLAY INVISIBLE (-4750 2800);
FORCEPROP 1 LASTPIN (-4650 2750) $PN 1
J 0
(-4638 2762);
DISPLAY 0.787234 (-4638 2762);
PAINT MONO (-4638 2762);
FORCEPROP 1 LASTPIN (-4450 2750) $PN 2
J 0
(-4488 2762);
DISPLAY 0.787234 (-4488 2762);
PAINT MONO (-4488 2762);
FORCEPROP 1 LAST VALUE 0
J 2
(-4400 2750);
DISPLAY 0.510638 (-4400 2750);
FORCEPROP 1 LAST TOLERANCE 5%
J 0
(-4375 2750);
DISPLAY 0.510638 (-4375 2750);
FORCEPROP 1 LAST MATERIAL CHIP
J 0
(-4300 2750);
DISPLAY 0.510638 (-4300 2750);
FORCEPROP 2 LAST CDS_LIB pure_quanta
J 0
(-4550 2750);
DISPLAY INVISIBLE (-4550 2750);
FORCEPROP 1 LAST PACK_TYPE 0402LF
J 0
(-4300 2750);
DISPLAY 0.510638 (-4300 2750);
DISPLAY INVISIBLE (-4300 2750);
FORCEPROP 1 LAST WATTAGE 1/16W
J 2
(-4375 2825);
DISPLAY 0.404255 (-4375 2825);
DISPLAY INVISIBLE (-4375 2825);
FORCEPROP 1 LAST PATH I8
J 0
(-4600 2900);
DISPLAY 0.978723 (-4600 2900);
PAINT WHITE (-4600 2900);
DISPLAY INVISIBLE (-4600 2900);
FORCEPROP 1 LAST PART_NUMBER CS00002JB13
J 0
(-4600 2800);
DISPLAY 0.404255 (-4600 2800);
DISPLAY INVISIBLE (-4600 2800);
FORCEADD UNIVERSAL_GND..1
(-4775 3825);
FORCEPROP 3 LASTPIN (-4775 3875) SIG_NAME GND\g
J 0
(-4765 3885);
DISPLAY 0.659574 (-4765 3885);
PAINT MONO (-4765 3885);
DISPLAY INVISIBLE (-4765 3885);
FORCEPROP 2 LAST CDS_LIB pure_quanta_power
J 0
(-4775 3825);
DISPLAY INVISIBLE (-4775 3825);
FORCEPROP 1 LAST HDL_POWER GND
J 1
(-4750 3750);
DISPLAY 0.872340 (-4750 3750);
PAINT GREEN (-4750 3750);
DISPLAY INVISIBLE (-4750 3750);
FORCEPROP 1 LAST PATH I9
J 0
(-4700 3825);
DISPLAY 0.872340 (-4700 3825);
PAINT AQUA (-4700 3825);
DISPLAY INVISIBLE (-4700 3825);
FORCEADD QUANTA_TITLE_BLOCK_C..1
(0 0);
FORCEPROP 0 LAST CDS_CON_LAST_MODIFIED Thu Sep 14 16:12:37 2023
J 0
(-1885 15);
DISPLAY INVISIBLE (-1885 15);
FORCEPROP 1 LAST CUSTOM_TXT_CDS <CON_LAST_MODIFIED>
J 0
(-1885 15);
DISPLAY 0.978723 (-1885 15);
FORCEPROP 2 LAST CUSTOM_TXT_CDS <XR_PAGE_TITLE>
J 0
(-7890 5250);
DISPLAY 0.638298 (-7890 5250);
PAINT PINK (-7890 5250);
DISPLAY INVISIBLE (-7890 5250);
FORCEPROP 1 LAST CUSTOM_TXT_CDS <NAME_2>
J 0
(-3175 50);
FORCEPROP 1 LAST CUSTOM_TXT_CDS <NAME_1>
J 0
(-3175 175);
FORCEPROP 1 LAST CUSTOM_TXT_CDS <Q_NUMBER>
J 0
(-1403 103);
DISPLAY 1.212766 (-1403 103);
FORCEPROP 1 LAST CUSTOM_TXT_CDS <Q_PROJ>
J 0
(-2382 102);
DISPLAY 1.212766 (-2382 102);
FORCEPROP 1 LAST CUSTOM_TXT_CDS <Q_REV>
J 0
(-184 103);
DISPLAY 1.212766 (-184 103);
FORCEPROP 1 LAST CUSTOM_TXT_CDS <CON_PAGE_NUM> OF <CON_TOTAL_PAGES>
J 0
(-446 18);
DISPLAY 0.978723 (-446 18);
FORCEPROP 1 LAST Q_TITLE PWRGD_ISOLATOR
J 0
(-9366 26);
DISPLAY 2.446809 (-9366 26);
PAINT GREEN (-9366 26);
FORCEPROP 2 LAST PAGE_BORDER TRUE
J 0
(-7890 5250);
DISPLAY 0.638298 (-7890 5250);
PAINT PINK (-7890 5250);
DISPLAY INVISIBLE (-7890 5250);
FORCEPROP 1 LAST CDS_LMAN_SYM_OUTLINE -9475,6775,100,-125
J 0
(0 0);
DISPLAY 0.468085 (0 0);
PAINT GREEN (0 0);
DISPLAY INVISIBLE (0 0);
FORCEPROP 2 LAST CDS_LIB pure_quanta
J 0
(0 0);
DISPLAY INVISIBLE (0 0);
FORCEPROP 2 LAST CDS_XR_PAGE_TITLE CR-254 : @T6G_MB_LIB.T6G(SCH_1):PAGE254
J 0
(-7890 5250);
DISPLAY 0.638298 (-7890 5250);
PAINT PINK (-7890 5250);
DISPLAY INVISIBLE (-7890 5250);
FORCEPROP 1 LAST Q_DEPT BU9
J 1
(-3763 49);
DISPLAY 1.957447 (-3763 49);
PAINT GREEN (-3763 49);
DISPLAY INVISIBLE (-3763 49);
FORCEPROP 1 LAST COMMENT_BODY TRUE
J 0
(12 -13);
DISPLAY 0.978723 (12 -13);
PAINT GREEN (12 -13);
DISPLAY INVISIBLE (12 -13);
WIRE 16 -1 (-4775 4800)(-4775 4725);
WIRE 16 -1 (-5925 3700)(-5925 3575);
WIRE 16 -1 (-5925 4675)(-5925 4600);
WIRE 16 -1 (-4775 4000)(-4775 3875);
WIRE 16 2175 (-7575 3500)(-1425 3500);
WIRE 16 2175 (-7575 4950)(-7575 3500);
WIRE 16 2175 (-1425 4950)(-1425 3500);
WIRE 16 2175 (-7575 4950)(-1425 4950);
WIRE 16 -1 (-4775 4525)(-4775 4450);
WIRE 16 -1 (-3600 4450)(-4775 4450);
FORCEPROP 2 LAST SIG_NAME PWRGD_PS_PWROK_PLD_ISO
J 0
(-4710 4460);
DISPLAY 0.808511 (-4710 4460);
FORCEPROP 2 LASTPROP $XRERR UNIQUE?
J 0
(-4950 4460);
DISPLAY 0.638298 (-4950 4460);
PAINT MONO (-4950 4460);
DISPLAY INVISIBLE (-4950 4460);
WIRE 16 -1 (-4775 4450)(-4775 4400);
WIRE 16 -1 (-7100 3850)(-6175 3850);
FORCEPROP 2 LAST SIG_NAME PWRGD_PS_PWROK_PLD
J 0
(-6985 3860);
DISPLAY 0.851064 (-6985 3860);
PAINT WHITE (-6985 3860);
WIRE 16 -1 (-5925 4400)(-5925 4150);
WIRE 16 -1 (-5025 4150)(-5925 4150);
FORCEPROP 2 LAST SIG_NAME PWRGD_PS_PWROK_PLD_N
J 0
(-5860 4160);
DISPLAY 0.808511 (-5860 4160);
FORCEPROP 2 LASTPROP $XRERR UNIQUE?
J 0
(-6100 4160);
DISPLAY 0.638298 (-6100 4160);
PAINT MONO (-6100 4160);
DISPLAY INVISIBLE (-6100 4160);
WIRE 16 -1 (-5925 4100)(-5925 4150);
WIRE 16 -1 (-1900 4450)(-3400 4450);
FORCEPROP 2 LAST SIG_NAME PWRGD_PS_PWROK_PLD_ISO_R
J 0
(-2985 4460);
DISPLAY 0.851064 (-2985 4460);
PAINT WHITE (-2985 4460);
WIRE 16 -1 (-4900 2575)(-4650 2575);
WIRE 16 -1 (-4900 2750)(-4900 2575);
WIRE 16 -1 (-4900 2750)(-4650 2750);
WIRE 16 -1 (-5775 2750)(-4900 2750);
FORCEPROP 0 LAST CDS_PHYS_NET_NAME MB0_P12V_STBY_PWRGD
J 0
(-5750 2792);
PAINT MONO (-5750 2792);
DISPLAY INVISIBLE (-5750 2792);
FORCEPROP 0 LAST SIG_NAME MB0_P12V_STBY_PWRGD
J 0
(-5675 2760);
DISPLAY 0.680851 (-5675 2760);
PAINT WHITE (-5675 2760);
WIRE 16 -1 (-4450 2575)(-3075 2575);
FORCEPROP 2 LAST SIG_NAME PWRGD_PS_PWROK
J 0
(-4085 2585);
DISPLAY 0.638298 (-4085 2585);
PAINT WHITE (-4085 2585);
WIRE 16 -1 (-4450 2750)(-3075 2750);
FORCEPROP 0 LAST CDS_PHYS_NET_NAME PWRGD_PS_PWROK_PLD
J 0
(-4135 2790);
PAINT MONO (-4135 2790);
DISPLAY INVISIBLE (-4135 2790);
FORCEPROP 2 LAST SIG_NAME PWRGD_PS_PWROK_PLD
J 0
(-4085 2760);
DISPLAY 0.638298 (-4085 2760);
PAINT WHITE (-4085 2760);
DOT 1 (-5925 4150);
DOT 1 (-4900 2750);
DOT 1 (-4775 4450);
QUIT
